(kicad_pcb
	(version 20260206)
	(generator "pcbnew")
	(generator_version "10.0")
	(general
		(thickness 1.6)
		(legacy_teardrops no)
	)
	(paper "A4")
	(title_block
		(title "Wiwynn_Tioga_Pass_MB.brd")
		(comment 1 "Tioga Pass / footprint 1232 of 4770 (EU4G1), pads 1-43 of 43")
	)
	(layers
		(0 "F.Cu" signal "TOP")
		(4 "In1.Cu" signal "L2GND")
		(6 "In2.Cu" signal "L3")
		(8 "In3.Cu" signal "L4GND")
		(10 "In4.Cu" signal "L5")
		(12 "In5.Cu" signal "L6GND")
		(14 "In6.Cu" signal "L7VCC")
		(16 "In7.Cu" signal "L8VCC")
		(18 "In8.Cu" signal "L9GND")
		(20 "In9.Cu" signal "L10")
		(22 "In10.Cu" signal "L11GND")
		(24 "In11.Cu" signal "L12")
		(26 "In12.Cu" signal "L13GND")
		(2 "B.Cu" signal "BOTTOM")
		(9 "F.Adhes" user "F.Adhesive")
		(11 "B.Adhes" user "B.Adhesive")
		(13 "F.Paste" user "Package Geometry/Pastemask Top")
		(15 "B.Paste" user "Package Geometry/Pastemask Bottom")
		(5 "F.SilkS" user "Ref Des/Silkscreen Top")
		(7 "B.SilkS" user "Ref Des/Silkscreen Bottom")
		(1 "F.Mask" user "Board Geometry/Soldermask Top")
		(3 "B.Mask" user "Board Geometry/Soldermask Bottom")
		(17 "Dwgs.User" user "User.Drawings")
		(19 "Cmts.User" user "User.Comments")
		(21 "Eco1.User" user "User.Eco1")
		(23 "Eco2.User" user "User.Eco2")
		(25 "Edge.Cuts" user "Board Geometry/Outline")
		(27 "Margin" user)
		(31 "F.CrtYd" user "Package Geometry/Place Bound Top")
		(29 "B.CrtYd" user "Package Geometry/Place Bound Bottom")
		(35 "F.Fab" user "Ref Des/Assembly Top")
		(33 "B.Fab" user "Ref Des/Assembly Bottom")
	)
	(footprint ""
		(layer "F.Cu")
		(at 177.673 -13.335 90)
		(property "Reference" "EU4G1"
			(at 5.18033 -0.889 0)
			(unlocked yes)
			(layer "F.SilkS")
			(effects
				(font
					(size 0.7874 0.5842)
					(thickness 0.1524)
				)
				(justify left)
			)
		)
		(property "Value" ""
			(at 0 0 90)
			(layer "F.Fab")
			(effects
				(font
					(size 1.27 1.27)
				)
			)
		)
		(duplicate_pad_numbers_are_jumpers no)
		(pad "1" smd custom
			(at -2.8321 -2.249932 90)
			(size 0.06985 0.06985)
			(layers "F.Cu" "F.Mask" "F.Paste")
			(net "VR_PVPP_GHJ_SS")
			(options
				(clearance outline)
				(anchor circle)
			)
			(primitives
				(gr_poly
					(pts
						(arc
							(start 0.2413 -0.1397)
							(mid 0.381 0)
							(end 0.2413 0.1397)
						)
						(xy -0.381 0.1397) (xy -0.381 -0.1397)
					)
					(width 0)
					(fill yes)
				)
			)
		)
		(pad "2" smd custom
			(at -2.8321 -1.75006 90)
			(size 0.06985 0.06985)
			(layers "F.Cu" "F.Mask" "F.Paste")
			(net "VR_FB_PVPP_GHJ")
			(options
				(clearance outline)
				(anchor circle)
			)
			(primitives
				(gr_poly
					(pts
						(arc
							(start 0.2413 -0.1397)
							(mid 0.381 0)
							(end 0.2413 0.1397)
						)
						(xy -0.381 0.1397) (xy -0.381 -0.1397)
					)
					(width 0)
					(fill yes)
				)
			)
		)
		(pad "3" smd custom
			(at -2.8321 -1.249934 90)
			(size 0.06985 0.06985)
			(layers "F.Cu" "F.Mask" "F.Paste")
			(net "VR_COMP_PVPP_GHJ_3")
			(options
				(clearance outline)
				(anchor circle)
			)
			(primitives
				(gr_poly
					(pts
						(arc
							(start 0.2413 -0.1397)
							(mid 0.381 0)
							(end 0.2413 0.1397)
						)
						(xy -0.381 0.1397) (xy -0.381 -0.1397)
					)
					(width 0)
					(fill yes)
				)
			)
		)
		(pad "4" smd custom
			(at -2.8321 -0.750062 90)
			(size 0.06985 0.06985)
			(layers "F.Cu" "F.Mask" "F.Paste")
			(net "VR_PVPP_GHJ_ISET")
			(options
				(clearance outline)
				(anchor circle)
			)
			(primitives
				(gr_poly
					(pts
						(arc
							(start 0.2413 -0.1397)
							(mid 0.381 0)
							(end 0.2413 0.1397)
						)
						(xy -0.381 0.1397) (xy -0.381 -0.1397)
					)
					(width 0)
					(fill yes)
				)
			)
		)
		(pad "5" smd custom
			(at -2.8321 -0.249936 90)
			(size 0.06985 0.06985)
			(layers "F.Cu" "F.Mask" "F.Paste")
			(net "AGND_PVPP_GHJ")
			(options
				(clearance outline)
				(anchor circle)
			)
			(primitives
				(gr_poly
					(pts
						(arc
							(start 0.2413 -0.1397)
							(mid 0.381 0)
							(end 0.2413 0.1397)
						)
						(xy -0.381 0.1397) (xy -0.381 -0.1397)
					)
					(width 0)
					(fill yes)
				)
			)
		)
		(pad "6" smd custom
			(at -2.8321 0.249936 90)
			(size 0.06985 0.06985)
			(layers "F.Cu" "F.Mask" "F.Paste")
			(net "AGND_PVPP_GHJ")
			(options
				(clearance outline)
				(anchor circle)
			)
			(primitives
				(gr_poly
					(pts
						(arc
							(start 0.2413 -0.1397)
							(mid 0.381 0)
							(end 0.2413 0.1397)
						)
						(xy -0.381 0.1397) (xy -0.381 -0.1397)
					)
					(width 0)
					(fill yes)
				)
			)
		)
		(pad "7" smd custom
			(at -2.8321 0.750062 90)
			(size 0.06985 0.06985)
			(layers "F.Cu" "F.Mask" "F.Paste")
			(net "PWRGD_PVPP_GHJ_R")
			(options
				(clearance outline)
				(anchor circle)
			)
			(primitives
				(gr_poly
					(pts
						(arc
							(start 0.2413 -0.1397)
							(mid 0.381 0)
							(end 0.2413 0.1397)
						)
						(xy -0.381 0.1397) (xy -0.381 -0.1397)
					)
					(width 0)
					(fill yes)
				)
			)
		)
		(pad "8" smd custom
			(at -2.8321 1.249934 90)
			(size 0.06985 0.06985)
			(layers "F.Cu" "F.Mask" "F.Paste")
			(net "VR_FET_SW_P12V_STBY_PVPP_GHJ")
			(options
				(clearance outline)
				(anchor circle)
			)
			(primitives
				(gr_poly
					(pts
						(arc
							(start 0.2413 -0.1397)
							(mid 0.381 0)
							(end 0.2413 0.1397)
						)
						(xy -0.381 0.1397) (xy -0.381 -0.1397)
					)
					(width 0)
					(fill yes)
				)
			)
		)
		(pad "9" smd custom
			(at -2.8321 1.75006 90)
			(size 0.06985 0.06985)
			(layers "F.Cu" "F.Mask" "F.Paste")
			(net "VR_FET_SW_P12V_STBY_PVPP_GHJ")
			(options
				(clearance outline)
				(anchor circle)
			)
			(primitives
				(gr_poly
					(pts
						(arc
							(start 0.2413 -0.1397)
							(mid 0.381 0)
							(end 0.2413 0.1397)
						)
						(xy -0.381 0.1397) (xy -0.381 -0.1397)
					)
					(width 0)
					(fill yes)
				)
			)
		)
		(pad "10" smd custom
			(at -2.8321 2.249932 90)
			(size 0.06985 0.06985)
			(layers "F.Cu" "F.Mask" "F.Paste")
			(net "VR_FET_SW_P12V_STBY_PVPP_GHJ")
			(options
				(clearance outline)
				(anchor circle)
			)
			(primitives
				(gr_poly
					(pts
						(arc
							(start 0.2413 -0.1397)
							(mid 0.381 0)
							(end 0.2413 0.1397)
						)
						(xy -0.381 0.1397) (xy -0.381 -0.1397)
					)
					(width 0)
					(fill yes)
				)
			)
		)
		(pad "11" smd custom
			(at -2.249932 2.8321 90)
			(size 0.06985 0.06985)
			(layers "F.Cu" "F.Mask" "F.Paste")
			(net "VR_FET_SW_P12V_STBY_PVPP_GHJ")
			(options
				(clearance outline)
				(anchor circle)
			)
			(primitives
				(gr_poly
					(pts
						(arc
							(start -0.1397 -0.2413)
							(mid 0 -0.381)
							(end 0.1397 -0.2413)
						)
						(xy 0.1397 0.381) (xy -0.1397 0.381)
					)
					(width 0)
					(fill yes)
				)
			)
		)
		(pad "12" smd custom
			(at -1.75006 2.8321 90)
			(size 0.06985 0.06985)
			(layers "F.Cu" "F.Mask" "F.Paste")
			(net "VR_FET_SW_P12V_STBY_PVPP_GHJ")
			(options
				(clearance outline)
				(anchor circle)
			)
			(primitives
				(gr_poly
					(pts
						(arc
							(start -0.1397 -0.2413)
							(mid 0 -0.381)
							(end 0.1397 -0.2413)
						)
						(xy 0.1397 0.381) (xy -0.1397 0.381)
					)
					(width 0)
					(fill yes)
				)
			)
		)
		(pad "13" smd custom
			(at -1.249934 2.8321 90)
			(size 0.06985 0.06985)
			(layers "F.Cu" "F.Mask" "F.Paste")
			(net "VR_FET_SW_P12V_STBY_PVPP_GHJ")
			(options
				(clearance outline)
				(anchor circle)
			)
			(primitives
				(gr_poly
					(pts
						(arc
							(start -0.1397 -0.2413)
							(mid 0 -0.381)
							(end 0.1397 -0.2413)
						)
						(xy 0.1397 0.381) (xy -0.1397 0.381)
					)
					(width 0)
					(fill yes)
				)
			)
		)
		(pad "14" smd custom
			(at -0.750062 2.8321 90)
			(size 0.06985 0.06985)
			(layers "F.Cu" "F.Mask" "F.Paste")
			(net "VR_FET_SW_P12V_STBY_PVPP_GHJ")
			(options
				(clearance outline)
				(anchor circle)
			)
			(primitives
				(gr_poly
					(pts
						(arc
							(start -0.1397 -0.2413)
							(mid 0 -0.381)
							(end 0.1397 -0.2413)
						)
						(xy 0.1397 0.381) (xy -0.1397 0.381)
					)
					(width 0)
					(fill yes)
				)
			)
		)
		(pad "15" smd custom
			(at -0.249936 2.8321 90)
			(size 0.06985 0.06985)
			(layers "F.Cu" "F.Mask" "F.Paste")
			(net "VR_PVPP_GHJ_PHASE")
			(options
				(clearance outline)
				(anchor circle)
			)
			(primitives
				(gr_poly
					(pts
						(arc
							(start -0.1397 -0.2413)
							(mid 0 -0.381)
							(end 0.1397 -0.2413)
						)
						(xy 0.1397 0.381) (xy -0.1397 0.381)
					)
					(width 0)
					(fill yes)
				)
			)
		)
		(pad "16" smd custom
			(at 0.249936 2.8321 90)
			(size 0.06985 0.06985)
			(layers "F.Cu" "F.Mask" "F.Paste")
			(net "GND")
			(options
				(clearance outline)
				(anchor circle)
			)
			(primitives
				(gr_poly
					(pts
						(arc
							(start -0.1397 -0.2413)
							(mid 0 -0.381)
							(end 0.1397 -0.2413)
						)
						(xy 0.1397 0.381) (xy -0.1397 0.381)
					)
					(width 0)
					(fill yes)
				)
			)
		)
		(pad "17" smd custom
			(at 0.750062 2.8321 90)
			(size 0.06985 0.06985)
			(layers "F.Cu" "F.Mask" "F.Paste")
			(net "GND")
			(options
				(clearance outline)
				(anchor circle)
			)
			(primitives
				(gr_poly
					(pts
						(arc
							(start -0.1397 -0.2413)
							(mid 0 -0.381)
							(end 0.1397 -0.2413)
						)
						(xy 0.1397 0.381) (xy -0.1397 0.381)
					)
					(width 0)
					(fill yes)
				)
			)
		)
		(pad "18" smd custom
			(at 1.249934 2.8321 90)
			(size 0.06985 0.06985)
			(layers "F.Cu" "F.Mask" "F.Paste")
			(net "GND")
			(options
				(clearance outline)
				(anchor circle)
			)
			(primitives
				(gr_poly
					(pts
						(arc
							(start -0.1397 -0.2413)
							(mid 0 -0.381)
							(end 0.1397 -0.2413)
						)
						(xy 0.1397 0.381) (xy -0.1397 0.381)
					)
					(width 0)
					(fill yes)
				)
			)
		)
		(pad "19" smd custom
			(at 1.75006 2.8321 90)
			(size 0.06985 0.06985)
			(layers "F.Cu" "F.Mask" "F.Paste")
			(net "GND")
			(options
				(clearance outline)
				(anchor circle)
			)
			(primitives
				(gr_poly
					(pts
						(arc
							(start -0.1397 -0.2413)
							(mid 0 -0.381)
							(end 0.1397 -0.2413)
						)
						(xy 0.1397 0.381) (xy -0.1397 0.381)
					)
					(width 0)
					(fill yes)
				)
			)
		)
		(pad "20" smd custom
			(at 2.249932 2.8321 90)
			(size 0.06985 0.06985)
			(layers "F.Cu" "F.Mask" "F.Paste")
			(net "GND")
			(options
				(clearance outline)
				(anchor circle)
			)
			(primitives
				(gr_poly
					(pts
						(arc
							(start -0.1397 -0.2413)
							(mid 0 -0.381)
							(end 0.1397 -0.2413)
						)
						(xy 0.1397 0.381) (xy -0.1397 0.381)
					)
					(width 0)
					(fill yes)
				)
			)
		)
		(pad "21" smd custom
			(at 2.8321 2.249932 90)
			(size 0.06985 0.06985)
			(layers "F.Cu" "F.Mask" "F.Paste")
			(net "GND")
			(options
				(clearance outline)
				(anchor circle)
			)
			(primitives
				(gr_poly
					(pts
						(arc
							(start -0.2413 0.1397)
							(mid -0.381 0)
							(end -0.2413 -0.1397)
						)
						(xy 0.381 -0.1397) (xy 0.381 0.1397)
					)
					(width 0)
					(fill yes)
				)
			)
		)
		(pad "22" smd custom
			(at 2.8321 1.75006 90)
			(size 0.06985 0.06985)
			(layers "F.Cu" "F.Mask" "F.Paste")
			(net "GND")
			(options
				(clearance outline)
				(anchor circle)
			)
			(primitives
				(gr_poly
					(pts
						(arc
							(start -0.2413 0.1397)
							(mid -0.381 0)
							(end -0.2413 -0.1397)
						)
						(xy 0.381 -0.1397) (xy 0.381 0.1397)
					)
					(width 0)
					(fill yes)
				)
			)
		)
		(pad "23" smd custom
			(at 2.8321 1.249934 90)
			(size 0.06985 0.06985)
			(layers "F.Cu" "F.Mask" "F.Paste")
			(net "GND")
			(options
				(clearance outline)
				(anchor circle)
			)
			(primitives
				(gr_poly
					(pts
						(arc
							(start -0.2413 0.1397)
							(mid -0.381 0)
							(end -0.2413 -0.1397)
						)
						(xy 0.381 -0.1397) (xy 0.381 0.1397)
					)
					(width 0)
					(fill yes)
				)
			)
		)
		(pad "24" smd custom
			(at 2.8321 0.750062 90)
			(size 0.06985 0.06985)
			(layers "F.Cu" "F.Mask" "F.Paste")
			(net "GND")
			(options
				(clearance outline)
				(anchor circle)
			)
			(primitives
				(gr_poly
					(pts
						(arc
							(start -0.2413 0.1397)
							(mid -0.381 0)
							(end -0.2413 -0.1397)
						)
						(xy 0.381 -0.1397) (xy 0.381 0.1397)
					)
					(width 0)
					(fill yes)
				)
			)
		)
		(pad "25" smd custom
			(at 2.8321 0.249936 90)
			(size 0.06985 0.06985)
			(layers "F.Cu" "F.Mask" "F.Paste")
			(net "GND")
			(options
				(clearance outline)
				(anchor circle)
			)
			(primitives
				(gr_poly
					(pts
						(arc
							(start -0.2413 0.1397)
							(mid -0.381 0)
							(end -0.2413 -0.1397)
						)
						(xy 0.381 -0.1397) (xy 0.381 0.1397)
					)
					(width 0)
					(fill yes)
				)
			)
		)
		(pad "26" smd custom
			(at 2.8321 -0.249936 90)
			(size 0.06985 0.06985)
			(layers "F.Cu" "F.Mask" "F.Paste")
			(net "GND")
			(options
				(clearance outline)
				(anchor circle)
			)
			(primitives
				(gr_poly
					(pts
						(arc
							(start -0.2413 0.1397)
							(mid -0.381 0)
							(end -0.2413 -0.1397)
						)
						(xy 0.381 -0.1397) (xy 0.381 0.1397)
					)
					(width 0)
					(fill yes)
				)
			)
		)
		(pad "27" smd custom
			(at 2.8321 -0.750062 90)
			(size 0.06985 0.06985)
			(layers "F.Cu" "F.Mask" "F.Paste")
			(net "GND")
			(options
				(clearance outline)
				(anchor circle)
			)
			(primitives
				(gr_poly
					(pts
						(arc
							(start -0.2413 0.1397)
							(mid -0.381 0)
							(end -0.2413 -0.1397)
						)
						(xy 0.381 -0.1397) (xy 0.381 0.1397)
					)
					(width 0)
					(fill yes)
				)
			)
		)
		(pad "28" smd custom
			(at 2.8321 -1.249934 90)
			(size 0.06985 0.06985)
			(layers "F.Cu" "F.Mask" "F.Paste")
			(net "GND")
			(options
				(clearance outline)
				(anchor circle)
			)
			(primitives
				(gr_poly
					(pts
						(arc
							(start -0.2413 0.1397)
							(mid -0.381 0)
							(end -0.2413 -0.1397)
						)
						(xy 0.381 -0.1397) (xy 0.381 0.1397)
					)
					(width 0)
					(fill yes)
				)
			)
		)
		(pad "29" smd custom
			(at 2.8321 -1.75006 90)
			(size 0.06985 0.06985)
			(layers "F.Cu" "F.Mask" "F.Paste")
			(net "VR_PVPP_GHJ_PHASE")
			(options
				(clearance outline)
				(anchor circle)
			)
			(primitives
				(gr_poly
					(pts
						(arc
							(start -0.2413 0.1397)
							(mid -0.381 0)
							(end -0.2413 -0.1397)
						)
						(xy 0.381 -0.1397) (xy 0.381 0.1397)
					)
					(width 0)
					(fill yes)
				)
			)
		)
		(pad "30" smd custom
			(at 2.8321 -2.249932 90)
			(size 0.06985 0.06985)
			(layers "F.Cu" "F.Mask" "F.Paste")
			(net "VR_PVPP_GHJ_PHASE")
			(options
				(clearance outline)
				(anchor circle)
			)
			(primitives
				(gr_poly
					(pts
						(arc
							(start -0.2413 0.1397)
							(mid -0.381 0)
							(end -0.2413 -0.1397)
						)
						(xy 0.381 -0.1397) (xy 0.381 0.1397)
					)
					(width 0)
					(fill yes)
				)
			)
		)
		(pad "31" smd custom
			(at 2.249932 -2.8321 90)
			(size 0.06985 0.06985)
			(layers "F.Cu" "F.Mask" "F.Paste")
			(net "VR_PVPP_GHJ_PHASE")
			(options
				(clearance outline)
				(anchor circle)
			)
			(primitives
				(gr_poly
					(pts
						(arc
							(start 0.1397 0.2413)
							(mid 0 0.381)
							(end -0.1397 0.2413)
						)
						(xy -0.1397 -0.381) (xy 0.1397 -0.381)
					)
					(width 0)
					(fill yes)
				)
			)
		)
		(pad "32" smd custom
			(at 1.75006 -2.8321 90)
			(size 0.06985 0.06985)
			(layers "F.Cu" "F.Mask" "F.Paste")
			(net "VR_PVPP_GHJ_PHASE")
			(options
				(clearance outline)
				(anchor circle)
			)
			(primitives
				(gr_poly
					(pts
						(arc
							(start 0.1397 0.2413)
							(mid 0 0.381)
							(end -0.1397 0.2413)
						)
						(xy -0.1397 -0.381) (xy 0.1397 -0.381)
					)
					(width 0)
					(fill yes)
				)
			)
		)
		(pad "33" smd custom
			(at 1.249934 -2.8321 90)
			(size 0.06985 0.06985)
			(layers "F.Cu" "F.Mask" "F.Paste")
			(net "VR_PVPP_GHJ_PHASE")
			(options
				(clearance outline)
				(anchor circle)
			)
			(primitives
				(gr_poly
					(pts
						(arc
							(start 0.1397 0.2413)
							(mid 0 0.381)
							(end -0.1397 0.2413)
						)
						(xy -0.1397 -0.381) (xy 0.1397 -0.381)
					)
					(width 0)
					(fill yes)
				)
			)
		)
		(pad "34" smd custom
			(at 0.750062 -2.8321 90)
			(size 0.06985 0.06985)
			(layers "F.Cu" "F.Mask" "F.Paste")
			(net "VR_PVPP_GHJ_PHASE")
			(options
				(clearance outline)
				(anchor circle)
			)
			(primitives
				(gr_poly
					(pts
						(arc
							(start 0.1397 0.2413)
							(mid 0 0.381)
							(end -0.1397 0.2413)
						)
						(xy -0.1397 -0.381) (xy 0.1397 -0.381)
					)
					(width 0)
					(fill yes)
				)
			)
		)
		(pad "35" smd custom
			(at 0.249936 -2.8321 90)
			(size 0.06985 0.06985)
			(layers "F.Cu" "F.Mask" "F.Paste")
			(net "VR_PVPP_GHJ_PHASE")
			(options
				(clearance outline)
				(anchor circle)
			)
			(primitives
				(gr_poly
					(pts
						(arc
							(start 0.1397 0.2413)
							(mid 0 0.381)
							(end -0.1397 0.2413)
						)
						(xy -0.1397 -0.381) (xy 0.1397 -0.381)
					)
					(width 0)
					(fill yes)
				)
			)
		)
		(pad "36" smd custom
			(at -0.249936 -2.8321 90)
			(size 0.06985 0.06985)
			(layers "F.Cu" "F.Mask" "F.Paste")
			(net "VR_PVPP_GHJ_BOOT")
			(options
				(clearance outline)
				(anchor circle)
			)
			(primitives
				(gr_poly
					(pts
						(arc
							(start 0.1397 0.2413)
							(mid 0 0.381)
							(end -0.1397 0.2413)
						)
						(xy -0.1397 -0.381) (xy 0.1397 -0.381)
					)
					(width 0)
					(fill yes)
				)
			)
		)
		(pad "37" smd custom
			(at -0.750062 -2.8321 90)
			(size 0.06985 0.06985)
			(layers "F.Cu" "F.Mask" "F.Paste")
			(net "GND")
			(options
				(clearance outline)
				(anchor circle)
			)
			(primitives
				(gr_poly
					(pts
						(arc
							(start 0.1397 0.2413)
							(mid 0 0.381)
							(end -0.1397 0.2413)
						)
						(xy -0.1397 -0.381) (xy 0.1397 -0.381)
					)
					(width 0)
					(fill yes)
				)
			)
		)
		(pad "38" smd custom
			(at -1.249934 -2.8321 90)
			(size 0.06985 0.06985)
			(layers "F.Cu" "F.Mask" "F.Paste")
			(net "VR_VB_PVPP_GHJ")
			(options
				(clearance outline)
				(anchor circle)
			)
			(primitives
				(gr_poly
					(pts
						(arc
							(start 0.1397 0.2413)
							(mid 0 0.381)
							(end -0.1397 0.2413)
						)
						(xy -0.1397 -0.381) (xy 0.1397 -0.381)
					)
					(width 0)
					(fill yes)
				)
			)
		)
		(pad "39" smd custom
			(at -1.75006 -2.8321 90)
			(size 0.06985 0.06985)
			(layers "F.Cu" "F.Mask" "F.Paste")
			(net "VR_FET_SW_P12V_STBY_PVPP_GHJ")
			(options
				(clearance outline)
				(anchor circle)
			)
			(primitives
				(gr_poly
					(pts
						(arc
							(start 0.1397 0.2413)
							(mid 0 0.381)
							(end -0.1397 0.2413)
						)
						(xy -0.1397 -0.381) (xy 0.1397 -0.381)
					)
					(width 0)
					(fill yes)
				)
			)
		)
		(pad "40" smd custom
			(at -2.249932 -2.8321 90)
			(size 0.06985 0.06985)
			(layers "F.Cu" "F.Mask" "F.Paste")
			(net "FM_PVPP_PVDDQ_CPU1_EN_GHJ")
			(options
				(clearance outline)
				(anchor circle)
			)
			(primitives
				(gr_poly
					(pts
						(arc
							(start 0.1397 0.2413)
							(mid 0 0.381)
							(end -0.1397 0.2413)
						)
						(xy -0.1397 -0.381) (xy 0.1397 -0.381)
					)
					(width 0)
					(fill yes)
				)
			)
		)
		(pad "41" smd rect
			(at -1.4478 -1.1938 90)
			(size 1.4986 2.0066)
			(layers "F.Cu" "F.Mask" "F.Paste")
			(net "GND")
		)
		(pad "42" smd rect
			(at -1.4478 1.1938 90)
			(size 1.4986 2.0066)
			(layers "F.Cu" "F.Mask" "F.Paste")
			(net "VR_FET_SW_P12V_STBY_PVPP_GHJ")
		)
		(pad "43" smd rect
			(at 1.0033 0 90)
			(size 2.3876 4.3942)
			(layers "F.Cu" "F.Mask" "F.Paste")
			(net "VR_PVPP_GHJ_PHASE")
		)
	)
)
